(kicad_pcb
	(version 20260206)
	(generator "pcbnew")
	(generator_version "10.0")
	(general
		(thickness 1.6)
		(legacy_teardrops no)
	)
	(paper "A4")
	(title_block
		(title "12092022_DA0F0TFB6D0_F0T_FAN_BOARD_MP5048_D_brd_v02_OCP.brd")
		(comment 1 "Grand Teton / footprints 522-528 of 924")
	)
	(layers
		(0 "F.Cu" signal "TOP")
		(4 "In1.Cu" signal "GND")
		(6 "In2.Cu" signal "IN1")
		(8 "In3.Cu" signal "IN2")
		(10 "In4.Cu" signal "GND1")
		(2 "B.Cu" signal "BOTTOM")
		(9 "F.Adhes" user "F.Adhesive")
		(11 "B.Adhes" user "B.Adhesive")
		(13 "F.Paste" user "Package Geometry/Pastemask Top")
		(15 "B.Paste" user "Package Geometry/Pastemask Bottom")
		(5 "F.SilkS" user "Ref Des/Silkscreen Top")
		(7 "B.SilkS" user "Ref Des/Silkscreen Bottom")
		(1 "F.Mask" user "Board Geometry/Soldermask Top")
		(3 "B.Mask" user "Board Geometry/Soldermask Bottom")
		(17 "Dwgs.User" user "User.Drawings")
		(19 "Cmts.User" user "User.Comments")
		(21 "Eco1.User" user "User.Eco1")
		(23 "Eco2.User" user "User.Eco2")
		(25 "Edge.Cuts" user "Board Geometry/Outline")
		(27 "Margin" user)
		(31 "F.CrtYd" user "Package Geometry/Place Bound Top")
		(29 "B.CrtYd" user "Package Geometry/Place Bound Bottom")
		(35 "F.Fab" user "Ref Des/Assembly Top")
		(33 "B.Fab" user "Ref Des/Assembly Bottom")
	)
	(footprint ""
		(layer "F.Cu")
		(at 17.907 -120.65)
		(property "Reference" "C2035"
			(at 0 0 0)
			(layer "F.SilkS")
			(hide yes)
			(effects
				(font
					(size 1.27 1.27)
				)
			)
		)
		(property "Value" ""
			(at 0 0 0)
			(layer "F.Fab")
			(effects
				(font
					(size 1.27 1.27)
				)
			)
		)
		(duplicate_pad_numbers_are_jumpers no)
		(fp_line
			(start -0.7874 -0.4064)
			(end 0.7874 -0.4064)
			(stroke
				(width 0.1524)
				(type default)
			)
			(layer "F.SilkS")
		)
		(fp_line
			(start -0.7874 0.4064)
			(end -0.7874 -0.4064)
			(stroke
				(width 0.1524)
				(type default)
			)
			(layer "F.SilkS")
		)
		(fp_line
			(start 0.7874 -0.4064)
			(end 0.7874 0.4064)
			(stroke
				(width 0.1524)
				(type default)
			)
			(layer "F.SilkS")
		)
		(fp_line
			(start 0.7874 0.4064)
			(end -0.7874 0.4064)
			(stroke
				(width 0.1524)
				(type default)
			)
			(layer "F.SilkS")
		)
		(fp_line
			(start -0.67945 -0.305054)
			(end -0.12065 -0.305054)
			(stroke
				(width 0.1)
				(type default)
			)
			(layer "F.Fab")
		)
		(fp_line
			(start -0.67945 0.3048)
			(end -0.67945 -0.305054)
			(stroke
				(width 0.1)
				(type default)
			)
			(layer "F.Fab")
		)
		(fp_line
			(start -0.12065 -0.305054)
			(end -0.12065 -0.2794)
			(stroke
				(width 0.1)
				(type default)
			)
			(layer "F.Fab")
		)
		(fp_line
			(start -0.12065 -0.2794)
			(end 0.12065 -0.2794)
			(stroke
				(width 0.1)
				(type default)
			)
			(layer "F.Fab")
		)
		(fp_line
			(start -0.12065 0.2794)
			(end -0.12065 0.3048)
			(stroke
				(width 0.1)
				(type default)
			)
			(layer "F.Fab")
		)
		(fp_line
			(start -0.12065 0.3048)
			(end -0.67945 0.3048)
			(stroke
				(width 0.1)
				(type default)
			)
			(layer "F.Fab")
		)
		(fp_line
			(start 0.120396 0.2794)
			(end -0.12065 0.2794)
			(stroke
				(width 0.1)
				(type default)
			)
			(layer "F.Fab")
		)
		(fp_line
			(start 0.120396 0.3048)
			(end 0.120396 0.2794)
			(stroke
				(width 0.1)
				(type default)
			)
			(layer "F.Fab")
		)
		(fp_line
			(start 0.12065 -0.3048)
			(end 0.67945 -0.3048)
			(stroke
				(width 0.1)
				(type default)
			)
			(layer "F.Fab")
		)
		(fp_line
			(start 0.12065 -0.2794)
			(end 0.12065 -0.3048)
			(stroke
				(width 0.1)
				(type default)
			)
			(layer "F.Fab")
		)
		(fp_line
			(start 0.67945 -0.3048)
			(end 0.67945 0.3048)
			(stroke
				(width 0.1)
				(type default)
			)
			(layer "F.Fab")
		)
		(fp_line
			(start 0.67945 0.3048)
			(end 0.120396 0.3048)
			(stroke
				(width 0.1)
				(type default)
			)
			(layer "F.Fab")
		)
		(pad "1" smd circle
			(at -0.40005 0)
			(size 0 0)
			(layers "F.Cu" "F.Mask" "F.Paste")
			(net "FAN_5_TACH_OL_R")
		)
		(pad "2" smd circle
			(at 0.40005 0)
			(size 0 0)
			(layers "F.Cu" "F.Mask" "F.Paste")
			(net "GND")
		)
	)
	(footprint ""
		(layer "F.Cu")
		(at 27.432 -189.23 180)
		(property "Reference" "R5491"
			(at 0 0 180)
			(layer "F.SilkS")
			(hide yes)
			(effects
				(font
					(size 1.27 1.27)
				)
			)
		)
		(property "Value" ""
			(at 0 0 180)
			(layer "F.Fab")
			(effects
				(font
					(size 1.27 1.27)
				)
			)
		)
		(duplicate_pad_numbers_are_jumpers no)
		(fp_line
			(start 0.7874 0.4064)
			(end -0.7874 0.4064)
			(stroke
				(width 0.1524)
				(type default)
			)
			(layer "F.SilkS")
		)
		(fp_line
			(start 0.7874 -0.4064)
			(end 0.7874 0.4064)
			(stroke
				(width 0.1524)
				(type default)
			)
			(layer "F.SilkS")
		)
		(fp_line
			(start -0.7874 0.4064)
			(end -0.7874 -0.4064)
			(stroke
				(width 0.1524)
				(type default)
			)
			(layer "F.SilkS")
		)
		(fp_line
			(start -0.7874 -0.4064)
			(end 0.7874 -0.4064)
			(stroke
				(width 0.1524)
				(type default)
			)
			(layer "F.SilkS")
		)
		(fp_line
			(start 0.67945 0.3048)
			(end 0.120396 0.3048)
			(stroke
				(width 0.1)
				(type default)
			)
			(layer "F.Fab")
		)
		(fp_line
			(start 0.67945 -0.3048)
			(end 0.67945 0.3048)
			(stroke
				(width 0.1)
				(type default)
			)
			(layer "F.Fab")
		)
		(fp_line
			(start 0.12065 -0.2794)
			(end 0.12065 -0.3048)
			(stroke
				(width 0.1)
				(type default)
			)
			(layer "F.Fab")
		)
		(fp_line
			(start 0.12065 -0.3048)
			(end 0.67945 -0.3048)
			(stroke
				(width 0.1)
				(type default)
			)
			(layer "F.Fab")
		)
		(fp_line
			(start 0.120396 0.3048)
			(end 0.120396 0.2794)
			(stroke
				(width 0.1)
				(type default)
			)
			(layer "F.Fab")
		)
		(fp_line
			(start 0.120396 0.2794)
			(end -0.12065 0.2794)
			(stroke
				(width 0.1)
				(type default)
			)
			(layer "F.Fab")
		)
		(fp_line
			(start -0.12065 0.3048)
			(end -0.67945 0.3048)
			(stroke
				(width 0.1)
				(type default)
			)
			(layer "F.Fab")
		)
		(fp_line
			(start -0.12065 0.2794)
			(end -0.12065 0.3048)
			(stroke
				(width 0.1)
				(type default)
			)
			(layer "F.Fab")
		)
		(fp_line
			(start -0.12065 -0.2794)
			(end 0.12065 -0.2794)
			(stroke
				(width 0.1)
				(type default)
			)
			(layer "F.Fab")
		)
		(fp_line
			(start -0.12065 -0.305054)
			(end -0.12065 -0.2794)
			(stroke
				(width 0.1)
				(type default)
			)
			(layer "F.Fab")
		)
		(fp_line
			(start -0.67945 0.3048)
			(end -0.67945 -0.305054)
			(stroke
				(width 0.1)
				(type default)
			)
			(layer "F.Fab")
		)
		(fp_line
			(start -0.67945 -0.305054)
			(end -0.12065 -0.305054)
			(stroke
				(width 0.1)
				(type default)
			)
			(layer "F.Fab")
		)
		(pad "1" smd circle
			(at -0.40005 0 180)
			(size 0 0)
			(layers "F.Cu" "F.Mask" "F.Paste")
			(net "P52V_FAN_4_BUFF_EN")
		)
		(pad "2" smd circle
			(at 0.40005 0 180)
			(size 0 0)
			(layers "F.Cu" "F.Mask" "F.Paste")
			(net "P52V_FAN_4_BUFF_EN_R")
		)
	)
	(footprint ""
		(layer "F.Cu")
		(at 17.272 -143.891 -90)
		(property "Reference" "R5524"
			(at 0 0 270)
			(layer "F.SilkS")
			(hide yes)
			(effects
				(font
					(size 1.27 1.27)
				)
			)
		)
		(property "Value" ""
			(at 0 0 270)
			(layer "F.Fab")
			(effects
				(font
					(size 1.27 1.27)
				)
			)
		)
		(duplicate_pad_numbers_are_jumpers no)
		(fp_line
			(start -0.7874 0.4064)
			(end -0.7874 -0.4064)
			(stroke
				(width 0.1524)
				(type default)
			)
			(layer "F.SilkS")
		)
		(fp_line
			(start 0.7874 0.4064)
			(end -0.7874 0.4064)
			(stroke
				(width 0.1524)
				(type default)
			)
			(layer "F.SilkS")
		)
		(fp_line
			(start -0.7874 -0.4064)
			(end 0.7874 -0.4064)
			(stroke
				(width 0.1524)
				(type default)
			)
			(layer "F.SilkS")
		)
		(fp_line
			(start 0.7874 -0.4064)
			(end 0.7874 0.4064)
			(stroke
				(width 0.1524)
				(type default)
			)
			(layer "F.SilkS")
		)
		(fp_line
			(start -0.67945 0.3048)
			(end -0.67945 -0.305054)
			(stroke
				(width 0.1)
				(type default)
			)
			(layer "F.Fab")
		)
		(fp_line
			(start -0.12065 0.3048)
			(end -0.67945 0.3048)
			(stroke
				(width 0.1)
				(type default)
			)
			(layer "F.Fab")
		)
		(fp_line
			(start 0.120396 0.3048)
			(end 0.120396 0.2794)
			(stroke
				(width 0.1)
				(type default)
			)
			(layer "F.Fab")
		)
		(fp_line
			(start 0.67945 0.3048)
			(end 0.120396 0.3048)
			(stroke
				(width 0.1)
				(type default)
			)
			(layer "F.Fab")
		)
		(fp_line
			(start -0.12065 0.2794)
			(end -0.12065 0.3048)
			(stroke
				(width 0.1)
				(type default)
			)
			(layer "F.Fab")
		)
		(fp_line
			(start 0.120396 0.2794)
			(end -0.12065 0.2794)
			(stroke
				(width 0.1)
				(type default)
			)
			(layer "F.Fab")
		)
		(fp_line
			(start -0.12065 -0.2794)
			(end 0.12065 -0.2794)
			(stroke
				(width 0.1)
				(type default)
			)
			(layer "F.Fab")
		)
		(fp_line
			(start 0.12065 -0.2794)
			(end 0.12065 -0.3048)
			(stroke
				(width 0.1)
				(type default)
			)
			(layer "F.Fab")
		)
		(fp_line
			(start 0.12065 -0.3048)
			(end 0.67945 -0.3048)
			(stroke
				(width 0.1)
				(type default)
			)
			(layer "F.Fab")
		)
		(fp_line
			(start 0.67945 -0.3048)
			(end 0.67945 0.3048)
			(stroke
				(width 0.1)
				(type default)
			)
			(layer "F.Fab")
		)
		(fp_line
			(start -0.67945 -0.305054)
			(end -0.12065 -0.305054)
			(stroke
				(width 0.1)
				(type default)
			)
			(layer "F.Fab")
		)
		(fp_line
			(start -0.12065 -0.305054)
			(end -0.12065 -0.2794)
			(stroke
				(width 0.1)
				(type default)
			)
			(layer "F.Fab")
		)
		(pad "1" smd circle
			(at -0.40005 0 270)
			(size 0 0)
			(layers "F.Cu" "F.Mask" "F.Paste")
			(net "PD_TCA9548_SML1_U321_A0")
		)
		(pad "2" smd circle
			(at 0.40005 0 270)
			(size 0 0)
			(layers "F.Cu" "F.Mask" "F.Paste")
			(net "GND")
		)
	)
	(footprint ""
		(layer "F.Cu")
		(at 47.752 -315.087 180)
		(property "Reference" "R5647"
			(at 0 0 180)
			(layer "F.SilkS")
			(hide yes)
			(effects
				(font
					(size 1.27 1.27)
				)
			)
		)
		(property "Value" ""
			(at 0 0 180)
			(layer "F.Fab")
			(effects
				(font
					(size 1.27 1.27)
				)
			)
		)
		(duplicate_pad_numbers_are_jumpers no)
		(fp_line
			(start 0.7874 0.4064)
			(end -0.7874 0.4064)
			(stroke
				(width 0.1524)
				(type default)
			)
			(layer "F.SilkS")
		)
		(fp_line
			(start 0.7874 -0.4064)
			(end 0.7874 0.4064)
			(stroke
				(width 0.1524)
				(type default)
			)
			(layer "F.SilkS")
		)
		(fp_line
			(start -0.7874 0.4064)
			(end -0.7874 -0.4064)
			(stroke
				(width 0.1524)
				(type default)
			)
			(layer "F.SilkS")
		)
		(fp_line
			(start -0.7874 -0.4064)
			(end 0.7874 -0.4064)
			(stroke
				(width 0.1524)
				(type default)
			)
			(layer "F.SilkS")
		)
		(fp_line
			(start 0.67945 0.3048)
			(end 0.120396 0.3048)
			(stroke
				(width 0.1)
				(type default)
			)
			(layer "F.Fab")
		)
		(fp_line
			(start 0.67945 -0.3048)
			(end 0.67945 0.3048)
			(stroke
				(width 0.1)
				(type default)
			)
			(layer "F.Fab")
		)
		(fp_line
			(start 0.12065 -0.2794)
			(end 0.12065 -0.3048)
			(stroke
				(width 0.1)
				(type default)
			)
			(layer "F.Fab")
		)
		(fp_line
			(start 0.12065 -0.3048)
			(end 0.67945 -0.3048)
			(stroke
				(width 0.1)
				(type default)
			)
			(layer "F.Fab")
		)
		(fp_line
			(start 0.120396 0.3048)
			(end 0.120396 0.2794)
			(stroke
				(width 0.1)
				(type default)
			)
			(layer "F.Fab")
		)
		(fp_line
			(start 0.120396 0.2794)
			(end -0.12065 0.2794)
			(stroke
				(width 0.1)
				(type default)
			)
			(layer "F.Fab")
		)
		(fp_line
			(start -0.12065 0.3048)
			(end -0.67945 0.3048)
			(stroke
				(width 0.1)
				(type default)
			)
			(layer "F.Fab")
		)
		(fp_line
			(start -0.12065 0.2794)
			(end -0.12065 0.3048)
			(stroke
				(width 0.1)
				(type default)
			)
			(layer "F.Fab")
		)
		(fp_line
			(start -0.12065 -0.2794)
			(end 0.12065 -0.2794)
			(stroke
				(width 0.1)
				(type default)
			)
			(layer "F.Fab")
		)
		(fp_line
			(start -0.12065 -0.305054)
			(end -0.12065 -0.2794)
			(stroke
				(width 0.1)
				(type default)
			)
			(layer "F.Fab")
		)
		(fp_line
			(start -0.67945 0.3048)
			(end -0.67945 -0.305054)
			(stroke
				(width 0.1)
				(type default)
			)
			(layer "F.Fab")
		)
		(fp_line
			(start -0.67945 -0.305054)
			(end -0.12065 -0.305054)
			(stroke
				(width 0.1)
				(type default)
			)
			(layer "F.Fab")
		)
		(pad "1" smd circle
			(at -0.40005 0 180)
			(size 0 0)
			(layers "F.Cu" "F.Mask" "F.Paste")
			(net "FAN_0_PRESENT")
		)
		(pad "2" smd circle
			(at 0.40005 0 180)
			(size 0 0)
			(layers "F.Cu" "F.Mask" "F.Paste")
			(net "GND")
		)
	)
	(footprint ""
		(layer "F.Cu")
		(at 25.850088 -241.909854)
		(property "Reference" "H2"
			(at -3.9878 -4.435348 0)
			(unlocked yes)
			(layer "F.SilkS")
			(effects
				(font
					(size 0.7874 0.5842)
					(thickness 0.1524)
				)
				(justify left)
			)
		)
		(property "Value" ""
			(at 0 0 0)
			(layer "F.Fab")
			(effects
				(font
					(size 1.27 1.27)
				)
			)
		)
		(duplicate_pad_numbers_are_jumpers no)
		(pad "1" thru_hole oval
			(at 0 0)
			(size 9.017 21.0058)
			(drill 3.0226
				(offset 0 5.999988)
			)
			(layers "*.Cu" "*.Mask")
			(remove_unused_layers no)
			(net "GND")
			(clearance -1.500378)
			(padstack
				(mode front_inner_back)
				(layer "Inner"
					(shape circle)
					(size 0 0)
					(clearance 0)
				)
				(layer "B.Cu"
					(shape oval)
					(size 9.017 21.0058)
					(offset 0 5.999988)
					(clearance -1.500378)
				)
			)
		)
	)
	(footprint ""
		(layer "F.Cu")
		(at 43.688 -258.826 90)
		(property "Reference" "PR3"
			(at 0 0 90)
			(layer "F.SilkS")
			(hide yes)
			(effects
				(font
					(size 1.27 1.27)
				)
			)
		)
		(property "Value" ""
			(at 0 0 90)
			(layer "F.Fab")
			(effects
				(font
					(size 1.27 1.27)
				)
			)
		)
		(duplicate_pad_numbers_are_jumpers no)
		(fp_line
			(start 0.7874 -0.4064)
			(end 0.7874 0.4064)
			(stroke
				(width 0.1524)
				(type default)
			)
			(layer "F.SilkS")
		)
		(fp_line
			(start -0.7874 -0.4064)
			(end 0.7874 -0.4064)
			(stroke
				(width 0.1524)
				(type default)
			)
			(layer "F.SilkS")
		)
		(fp_line
			(start 0.7874 0.4064)
			(end -0.7874 0.4064)
			(stroke
				(width 0.1524)
				(type default)
			)
			(layer "F.SilkS")
		)
		(fp_line
			(start -0.7874 0.4064)
			(end -0.7874 -0.4064)
			(stroke
				(width 0.1524)
				(type default)
			)
			(layer "F.SilkS")
		)
		(fp_line
			(start -0.12065 -0.305054)
			(end -0.12065 -0.2794)
			(stroke
				(width 0.1)
				(type default)
			)
			(layer "F.Fab")
		)
		(fp_line
			(start -0.67945 -0.305054)
			(end -0.12065 -0.305054)
			(stroke
				(width 0.1)
				(type default)
			)
			(layer "F.Fab")
		)
		(fp_line
			(start 0.67945 -0.3048)
			(end 0.67945 0.3048)
			(stroke
				(width 0.1)
				(type default)
			)
			(layer "F.Fab")
		)
		(fp_line
			(start 0.12065 -0.3048)
			(end 0.67945 -0.3048)
			(stroke
				(width 0.1)
				(type default)
			)
			(layer "F.Fab")
		)
		(fp_line
			(start 0.12065 -0.2794)
			(end 0.12065 -0.3048)
			(stroke
				(width 0.1)
				(type default)
			)
			(layer "F.Fab")
		)
		(fp_line
			(start -0.12065 -0.2794)
			(end 0.12065 -0.2794)
			(stroke
				(width 0.1)
				(type default)
			)
			(layer "F.Fab")
		)
		(fp_line
			(start 0.120396 0.2794)
			(end -0.12065 0.2794)
			(stroke
				(width 0.1)
				(type default)
			)
			(layer "F.Fab")
		)
		(fp_line
			(start -0.12065 0.2794)
			(end -0.12065 0.3048)
			(stroke
				(width 0.1)
				(type default)
			)
			(layer "F.Fab")
		)
		(fp_line
			(start 0.67945 0.3048)
			(end 0.120396 0.3048)
			(stroke
				(width 0.1)
				(type default)
			)
			(layer "F.Fab")
		)
		(fp_line
			(start 0.120396 0.3048)
			(end 0.120396 0.2794)
			(stroke
				(width 0.1)
				(type default)
			)
			(layer "F.Fab")
		)
		(fp_line
			(start -0.12065 0.3048)
			(end -0.67945 0.3048)
			(stroke
				(width 0.1)
				(type default)
			)
			(layer "F.Fab")
		)
		(fp_line
			(start -0.67945 0.3048)
			(end -0.67945 -0.305054)
			(stroke
				(width 0.1)
				(type default)
			)
			(layer "F.Fab")
		)
		(pad "1" smd rect
			(at -0.40005 0 270)
			(size 0.4572 0.508)
			(layers "F.Cu" "F.Mask" "F.Paste")
			(net "FAN_0_FAULT_R")
		)
		(pad "2" smd rect
			(at 0.40005 0 270)
			(size 0.4572 0.508)
			(layers "F.Cu" "F.Mask" "F.Paste")
			(net "FAN_0_FAULT")
		)
	)
	(footprint ""
		(layer "F.Cu")
		(at 37.465 -211.864956)
		(property "Reference" "R5196"
			(at 0 0 0)
			(layer "F.SilkS")
			(hide yes)
			(effects
				(font
					(size 1.27 1.27)
				)
			)
		)
		(property "Value" ""
			(at 0 0 0)
			(layer "F.Fab")
			(effects
				(font
					(size 1.27 1.27)
				)
			)
		)
		(duplicate_pad_numbers_are_jumpers no)
		(fp_line
			(start -0.7874 -0.4064)
			(end 0.7874 -0.4064)
			(stroke
				(width 0.1524)
				(type default)
			)
			(layer "F.SilkS")
		)
		(fp_line
			(start -0.7874 0.4064)
			(end -0.7874 -0.4064)
			(stroke
				(width 0.1524)
				(type default)
			)
			(layer "F.SilkS")
		)
		(fp_line
			(start 0.7874 -0.4064)
			(end 0.7874 0.4064)
			(stroke
				(width 0.1524)
				(type default)
			)
			(layer "F.SilkS")
		)
		(fp_line
			(start 0.7874 0.4064)
			(end -0.7874 0.4064)
			(stroke
				(width 0.1524)
				(type default)
			)
			(layer "F.SilkS")
		)
		(fp_line
			(start -0.67945 -0.305054)
			(end -0.12065 -0.305054)
			(stroke
				(width 0.1)
				(type default)
			)
			(layer "F.Fab")
		)
		(fp_line
			(start -0.67945 0.3048)
			(end -0.67945 -0.305054)
			(stroke
				(width 0.1)
				(type default)
			)
			(layer "F.Fab")
		)
		(fp_line
			(start -0.12065 -0.305054)
			(end -0.12065 -0.2794)
			(stroke
				(width 0.1)
				(type default)
			)
			(layer "F.Fab")
		)
		(fp_line
			(start -0.12065 -0.2794)
			(end 0.12065 -0.2794)
			(stroke
				(width 0.1)
				(type default)
			)
			(layer "F.Fab")
		)
		(fp_line
			(start -0.12065 0.2794)
			(end -0.12065 0.3048)
			(stroke
				(width 0.1)
				(type default)
			)
			(layer "F.Fab")
		)
		(fp_line
			(start -0.12065 0.3048)
			(end -0.67945 0.3048)
			(stroke
				(width 0.1)
				(type default)
			)
			(layer "F.Fab")
		)
		(fp_line
			(start 0.120396 0.2794)
			(end -0.12065 0.2794)
			(stroke
				(width 0.1)
				(type default)
			)
			(layer "F.Fab")
		)
		(fp_line
			(start 0.120396 0.3048)
			(end 0.120396 0.2794)
			(stroke
				(width 0.1)
				(type default)
			)
			(layer "F.Fab")
		)
		(fp_line
			(start 0.12065 -0.3048)
			(end 0.67945 -0.3048)
			(stroke
				(width 0.1)
				(type default)
			)
			(layer "F.Fab")
		)
		(fp_line
			(start 0.12065 -0.2794)
			(end 0.12065 -0.3048)
			(stroke
				(width 0.1)
				(type default)
			)
			(layer "F.Fab")
		)
		(fp_line
			(start 0.67945 -0.3048)
			(end 0.67945 0.3048)
			(stroke
				(width 0.1)
				(type default)
			)
			(layer "F.Fab")
		)
		(fp_line
			(start 0.67945 0.3048)
			(end 0.120396 0.3048)
			(stroke
				(width 0.1)
				(type default)
			)
			(layer "F.Fab")
		)
		(pad "1" smd circle
			(at -0.40005 0)
			(size 0 0)
			(layers "F.Cu" "F.Mask" "F.Paste")
			(net "FAN_1_PWM_OL")
		)
		(pad "2" smd circle
			(at 0.40005 0)
			(size 0 0)
			(layers "F.Cu" "F.Mask" "F.Paste")
			(net "FAN_1_PWM_OL_R")
		)
	)
)
